(kicad_pcb
	(version 20241229)
	(generator "pcbnew")
	(generator_version "9.0")
	(general
		(thickness 1.711)
		(legacy_teardrops no)
	)
	(paper "A4")
	(title_block
		(title "Antmicro Baseboard for Jetson AGX Thor")
		(date "2026-02-18")
		(rev "1.1.0")
		(company "Antmicro Ltd")
		(comment 1 "www.antmicro.com")
		(comment 9 "footprints 685-688 of 1170")
	)
	(layers
		(0 "F.Cu" signal)
		(4 "In1.Cu" signal)
		(6 "In2.Cu" signal)
		(8 "In3.Cu" signal)
		(10 "In4.Cu" jumper)
		(12 "In5.Cu" signal)
		(14 "In6.Cu" signal)
		(16 "In7.Cu" signal)
		(18 "In8.Cu" signal)
		(2 "B.Cu" signal)
		(9 "F.Adhes" user "F.Adhesive")
		(11 "B.Adhes" user "B.Adhesive")
		(13 "F.Paste" user)
		(15 "B.Paste" user)
		(5 "F.SilkS" user "F.Silkscreen")
		(7 "B.SilkS" user "B.Silkscreen")
		(1 "F.Mask" user)
		(3 "B.Mask" user)
		(17 "Dwgs.User" user "User.Drawings")
		(19 "Cmts.User" user "User.Comments")
		(21 "Eco1.User" user "User.Eco1")
		(23 "Eco2.User" user "User.Eco2")
		(25 "Edge.Cuts" user)
		(27 "Margin" user)
		(31 "F.CrtYd" user "F.Courtyard")
		(29 "B.CrtYd" user "B.Courtyard")
		(35 "F.Fab" user)
		(33 "B.Fab" user)
	)
	(footprint "antmicro-footprints:Tag-Connect_TC2050-IDC-NL_2x5_P1.27mm"
		(locked yes)
		(layer "B.Cu")
		(at 165 65.25 -90)
		(property "Reference" "J20"
			(at 2.89 -3.13 90)
			(layer "B.SilkS")
			(effects
				(font
					(size 0.7 0.7)
					(thickness 0.15)
				)
				(justify left bottom mirror)
			)
		)
		(property "Value" "Tag-Connect_TC2050-IDC-NL_2x5_P1.27mm"
			(at 0 -4.4 90)
			(layer "B.Fab")
			(effects
				(font
					(size 0.7 0.7)
					(thickness 0.15)
				)
				(justify left bottom mirror)
			)
		)
		(property "Datasheet" "https://www.tag-connect.com/wp-content/uploads/bsk-pdf-manager/TC2050-IDC-NL_Datasheet_8.pdf"
			(at 0 0 90)
			(layer "B.Fab")
			(hide yes)
			(effects
				(font
					(size 1.27 1.27)
					(thickness 0.15)
				)
				(justify mirror)
			)
		)
		(property "Description" "Tag Connect 2x5 1.27mm terminal"
			(at 0 0 90)
			(layer "B.Fab")
			(hide yes)
			(effects
				(font
					(size 1.27 1.27)
					(thickness 0.15)
				)
				(justify mirror)
			)
		)
		(property "MPN" "TC2050-IDC-NL"
			(at 0 0 90)
			(unlocked yes)
			(layer "B.Fab")
			(hide yes)
			(effects
				(font
					(size 1 1)
					(thickness 0.15)
				)
				(justify mirror)
			)
		)
		(property "Manufacturer" "Tag Connect"
			(at 0 0 90)
			(unlocked yes)
			(layer "B.Fab")
			(hide yes)
			(effects
				(font
					(size 1 1)
					(thickness 0.15)
				)
				(justify mirror)
			)
		)
		(property "Author" "Antmicro"
			(at 0 0 90)
			(unlocked yes)
			(layer "B.Fab")
			(hide yes)
			(effects
				(font
					(size 1 1)
					(thickness 0.15)
				)
				(justify mirror)
			)
		)
		(property "License" "Apache-2.0"
			(at 0 0 90)
			(unlocked yes)
			(layer "B.Fab")
			(hide yes)
			(effects
				(font
					(size 1 1)
					(thickness 0.15)
				)
				(justify mirror)
			)
		)
		(sheetname "/SoM_IO2/")
		(sheetfile "som_io2.kicad_sch")
		(attr exclude_from_bom)
		(fp_line
			(start -2.2 2.05)
			(end 4.7 2.05)
			(stroke
				(width 0.15)
				(type solid)
			)
			(layer "B.SilkS")
		)
		(fp_line
			(start 4.7 2.05)
			(end 5.1 1.7)
			(stroke
				(width 0.15)
				(type solid)
			)
			(layer "B.SilkS")
		)
		(fp_line
			(start 5.1 1.7)
			(end 5.1 -1.7)
			(stroke
				(width 0.15)
				(type solid)
			)
			(layer "B.SilkS")
		)
		(fp_line
			(start -5.08 0.900001)
			(end -2.2 2.05)
			(stroke
				(width 0.15)
				(type solid)
			)
			(layer "B.SilkS")
		)
		(fp_line
			(start -5.08 -0.8)
			(end -5.08 0.900001)
			(stroke
				(width 0.15)
				(type solid)
			)
			(layer "B.SilkS")
		)
		(fp_line
			(start -3.101001 -1.269)
			(end -3.101 -0.4)
			(stroke
				(width 0.15)
				(type solid)
			)
			(layer "B.SilkS")
		)
		(fp_line
			(start -2.3 -2.049)
			(end -5.08 -0.8)
			(stroke
				(width 0.15)
				(type solid)
			)
			(layer "B.SilkS")
		)
		(fp_line
			(start 4.7 -2.049)
			(end 5.1 -1.7)
			(stroke
				(width 0.15)
				(type solid)
			)
			(layer "B.SilkS")
		)
		(fp_line
			(start 4.7 -2.049)
			(end -2.3 -2.049)
			(stroke
				(width 0.15)
				(type solid)
			)
			(layer "B.SilkS")
		)
		(fp_line
			(start -2.3 2.3)
			(end 4.8 2.3)
			(stroke
				(width 0.05)
				(type solid)
			)
			(layer "B.CrtYd")
		)
		(fp_line
			(start 4.8 2.3)
			(end 5.32 1.8)
			(stroke
				(width 0.05)
				(type solid)
			)
			(layer "B.CrtYd")
		)
		(fp_line
			(start 5.32 1.8)
			(end 5.32 -1.8)
			(stroke
				(width 0.05)
				(type solid)
			)
			(layer "B.CrtYd")
		)
		(fp_line
			(start -5.330001 1.1)
			(end -2.3 2.3)
			(stroke
				(width 0.05)
				(type solid)
			)
			(layer "B.CrtYd")
		)
		(fp_line
			(start -5.33 -1)
			(end -5.330001 1.1)
			(stroke
				(width 0.05)
				(type solid)
			)
			(layer "B.CrtYd")
		)
		(fp_line
			(start -2.4 -2.29)
			(end -5.33 -1)
			(stroke
				(width 0.05)
				(type solid)
			)
			(layer "B.CrtYd")
		)
		(fp_line
			(start 4.8 -2.29)
			(end 5.32 -1.8)
			(stroke
				(width 0.05)
				(type solid)
			)
			(layer "B.CrtYd")
		)
		(fp_line
			(start 4.8 -2.29)
			(end -2.4 -2.29)
			(stroke
				(width 0.05)
				(type solid)
			)
			(layer "B.CrtYd")
		)
		(fp_text user "Author: Antmicro"
			(at -6.223 -7.249001 90)
			(layer "B.Fab")
			(effects
				(font
					(size 0.7 0.7)
					(thickness 0.15)
				)
				(justify left bottom mirror)
			)
		)
		(fp_text user "License: Apache-2.0"
			(at -6.223 -8.449 90)
			(layer "B.Fab")
			(effects
				(font
					(size 0.7 0.7)
					(thickness 0.15)
				)
				(justify left bottom mirror)
			)
		)
		(fp_text user "${REFERENCE}"
			(at -6.223 -6.048999 90)
			(layer "B.Fab")
			(effects
				(font
					(size 0.7 0.7)
					(thickness 0.15)
				)
				(justify left bottom mirror)
			)
		)
		(pad "" np_thru_hole circle
			(at -3.81 0 270)
			(size 0.9906 0.9906)
			(drill 0.9906)
			(layers "*.Cu" "*.Mask")
		)
		(pad "" np_thru_hole circle
			(at 3.809 -1.015 270)
			(size 0.9906 0.9906)
			(drill 0.9906)
			(layers "*.Cu" "*.Mask")
		)
		(pad "" np_thru_hole circle
			(at 3.809 1.016 270)
			(size 0.9906 0.9906)
			(drill 0.9906)
			(layers "*.Cu" "*.Mask")
		)
		(pad "1" connect circle
			(at -2.54 -0.634 270)
			(size 0.7874 0.7874)
			(layers "B.Cu" "B.Mask")
			(net 269 "/SoM_IO2/TC_VCC")
			(pinfunction "1")
			(pintype "passive")
		)
		(pad "2" connect circle
			(at -1.27 -0.634 270)
			(size 0.7874 0.7874)
			(layers "B.Cu" "B.Mask")
			(net 869 "/SoM_IO2/TC_JTAG_TMS")
			(pinfunction "2")
			(pintype "passive")
		)
		(pad "3" connect circle
			(at 0 -0.634 270)
			(size 0.7874 0.7874)
			(layers "B.Cu" "B.Mask")
			(net 1 "GND")
			(pinfunction "3")
			(pintype "passive")
		)
		(pad "4" connect circle
			(at 1.269 -0.634 270)
			(size 0.7874 0.7874)
			(layers "B.Cu" "B.Mask")
			(net 871 "/SoM_IO2/TC_JTAG_TCK")
			(pinfunction "4")
			(pintype "passive")
		)
		(pad "5" connect circle
			(at 2.539 -0.634 270)
			(size 0.7874 0.7874)
			(layers "B.Cu" "B.Mask")
			(net 1 "GND")
			(pinfunction "5")
			(pintype "passive")
		)
		(pad "6" connect circle
			(at 2.539 0.635 270)
			(size 0.7874 0.7874)
			(layers "B.Cu" "B.Mask")
			(net 872 "/SoM_IO2/TC_JTAG_TDO")
			(pinfunction "6")
			(pintype "passive")
		)
		(pad "7" connect circle
			(at 1.269 0.635 270)
			(size 0.7874 0.7874)
			(layers "B.Cu" "B.Mask")
			(net 867 "unconnected-(J20-Pad7)")
			(pinfunction "7")
			(pintype "passive+no_connect")
		)
		(pad "8" connect circle
			(at 0 0.635 270)
			(size 0.7874 0.7874)
			(layers "B.Cu" "B.Mask")
			(net 868 "/SoM_IO2/TC_JTAG_TDI")
			(pinfunction "8")
			(pintype "passive")
		)
		(pad "9" connect circle
			(at -1.27 0.635 270)
			(size 0.7874 0.7874)
			(layers "B.Cu" "B.Mask")
			(net 1 "GND")
			(pinfunction "9")
			(pintype "passive")
		)
		(pad "10" connect circle
			(at -2.54 0.635 270)
			(size 0.7874 0.7874)
			(layers "B.Cu" "B.Mask")
			(net 870 "/SoM_IO2/TC_JTAG_TRST_N")
			(pinfunction "10")
			(pintype "passive")
		)
	)
	(footprint "antmicro-footprints:R_0402_1005Metric"
		(layer "B.Cu")
		(at 177.5 57.5 -90)
		(descr "Resistor SMD 0402")
		(tags "resistor SMD 0402")
		(property "Reference" "R372"
			(at -3.602484 -0.415532 90)
			(layer "B.SilkS")
			(effects
				(font
					(size 0.7 0.7)
					(thickness 0.15)
				)
				(justify left bottom mirror)
			)
		)
		(property "Value" "R_1k_0402"
			(at -1.011843 -1.772047 90)
			(layer "B.Fab")
			(effects
				(font
					(size 0.7 0.7)
					(thickness 0.15)
				)
				(justify left bottom mirror)
			)
		)
		(property "Datasheet" "https://www.bourns.com/docs/product-datasheets/cr.pdf"
			(at 0 0 90)
			(layer "B.Fab")
			(hide yes)
			(effects
				(font
					(size 1.27 1.27)
					(thickness 0.15)
				)
				(justify mirror)
			)
		)
		(property "Description" "SMD Chip Resistor, 1 kohm, ± 1%, 63 mW, 0402 [1005 Metric], Thick Film, General Purpose"
			(at 0 0 90)
			(layer "B.Fab")
			(hide yes)
			(effects
				(font
					(size 1.27 1.27)
					(thickness 0.15)
				)
				(justify mirror)
			)
		)
		(property "MPN" "CR0402-FX-1001GLF"
			(at 0 0 90)
			(unlocked yes)
			(layer "B.Fab")
			(hide yes)
			(effects
				(font
					(size 1 1)
					(thickness 0.15)
				)
				(justify mirror)
			)
		)
		(property "Manufacturer" "Bourns"
			(at 0 0 90)
			(unlocked yes)
			(layer "B.Fab")
			(hide yes)
			(effects
				(font
					(size 1 1)
					(thickness 0.15)
				)
				(justify mirror)
			)
		)
		(property "License" "Apache-2.0"
			(at 0 0 90)
			(unlocked yes)
			(layer "B.Fab")
			(hide yes)
			(effects
				(font
					(size 1 1)
					(thickness 0.15)
				)
				(justify mirror)
			)
		)
		(property "Author" "Antmicro"
			(at 0 0 90)
			(unlocked yes)
			(layer "B.Fab")
			(hide yes)
			(effects
				(font
					(size 1 1)
					(thickness 0.15)
				)
				(justify mirror)
			)
		)
		(property "Val" "1k"
			(at 0 0 90)
			(unlocked yes)
			(layer "B.Fab")
			(hide yes)
			(effects
				(font
					(size 1 1)
					(thickness 0.15)
				)
				(justify mirror)
			)
		)
		(property "Tolerance" "1%"
			(at 0 0 90)
			(unlocked yes)
			(layer "B.Fab")
			(hide yes)
			(effects
				(font
					(size 1 1)
					(thickness 0.15)
				)
				(justify mirror)
			)
		)
		(sheetname "/Power/")
		(sheetfile "power.kicad_sch")
		(attr smd)
		(fp_rect
			(start -0.925 0.47)
			(end 0.925 -0.47)
			(stroke
				(width 0.05)
				(type default)
			)
			(fill no)
			(layer "B.CrtYd")
		)
		(fp_rect
			(start -0.5 0.25)
			(end 0.5 -0.25)
			(stroke
				(width 0.15)
				(type solid)
			)
			(fill no)
			(layer "B.Fab")
		)
		(fp_text user "Author: Antmicro"
			(at -0.95 -4.169 90)
			(layer "B.Fab")
			(effects
				(font
					(size 0.7 0.7)
					(thickness 0.15)
				)
				(justify left bottom mirror)
			)
		)
		(fp_text user "License: Apache-2.0"
			(at -0.95 -5.169 90)
			(layer "B.Fab")
			(effects
				(font
					(size 0.7 0.7)
					(thickness 0.15)
				)
				(justify left bottom mirror)
			)
		)
		(fp_text user "${REFERENCE}"
			(at -0.95 -3.168 90)
			(layer "B.Fab")
			(effects
				(font
					(size 0.7 0.7)
					(thickness 0.15)
				)
				(justify left bottom mirror)
			)
		)
		(pad "1" smd roundrect
			(at -0.48 0 270)
			(size 0.59 0.64)
			(layers "B.Cu" "B.Mask" "B.Paste")
			(roundrect_rratio 0.25)
			(net 46 "Net-(D63-A)")
			(pintype "passive")
		)
		(pad "2" smd roundrect
			(at 0.48 0 270)
			(size 0.59 0.64)
			(layers "B.Cu" "B.Mask" "B.Paste")
			(roundrect_rratio 0.25)
			(net 634 "+12V")
			(pintype "passive")
		)
	)
	(footprint "antmicro-footprints:SOT-523"
		(layer "B.Cu")
		(at 173.9 62.385002 -90)
		(property "Reference" "Q14"
			(at -0.982 1.362 90)
			(layer "B.SilkS")
			(effects
				(font
					(size 0.7 0.7)
					(thickness 0.15)
				)
				(justify left bottom mirror)
			)
		)
		(property "Value" "DMG1012T-7"
			(at 0.1 -1.824 90)
			(layer "B.Fab")
			(effects
				(font
					(size 0.7 0.7)
					(thickness 0.15)
				)
				(justify left bottom mirror)
			)
		)
		(property "Datasheet" "https://www.diodes.com/assets/Datasheets/ds31783.pdf"
			(at 0 0 90)
			(layer "B.Fab")
			(hide yes)
			(effects
				(font
					(size 1.27 1.27)
					(thickness 0.15)
				)
				(justify mirror)
			)
		)
		(property "Description" "Power MOSFET, N Channel, 20 V, 630 mA, 0.3 ohm, SOT-523, Surface Mount"
			(at 0 0 90)
			(layer "B.Fab")
			(hide yes)
			(effects
				(font
					(size 1.27 1.27)
					(thickness 0.15)
				)
				(justify mirror)
			)
		)
		(property "MPN" "DMG1012T-7"
			(at 0 0 90)
			(unlocked yes)
			(layer "B.Fab")
			(hide yes)
			(effects
				(font
					(size 1 1)
					(thickness 0.15)
				)
				(justify mirror)
			)
		)
		(property "Manufacturer" "Diodes Incorporated"
			(at 0 0 90)
			(unlocked yes)
			(layer "B.Fab")
			(hide yes)
			(effects
				(font
					(size 1 1)
					(thickness 0.15)
				)
				(justify mirror)
			)
		)
		(property "Author" "Antmicro"
			(at 0 0 90)
			(unlocked yes)
			(layer "B.Fab")
			(hide yes)
			(effects
				(font
					(size 1 1)
					(thickness 0.15)
				)
				(justify mirror)
			)
		)
		(property "License" "Apache-2.0"
			(at 0 0 90)
			(unlocked yes)
			(layer "B.Fab")
			(hide yes)
			(effects
				(font
					(size 1 1)
					(thickness 0.15)
				)
				(justify mirror)
			)
		)
		(sheetname "/Peripherals/")
		(sheetfile "peripherals.kicad_sch")
		(attr smd)
		(fp_line
			(start -0.725 0.551)
			(end -0.277 0.551)
			(stroke
				(width 0.15)
				(type solid)
			)
			(layer "B.SilkS")
		)
		(fp_line
			(start -0.277 0.551)
			(end -0.277 0.75)
			(stroke
				(width 0.15)
				(type solid)
			)
			(layer "B.SilkS")
		)
		(fp_line
			(start -0.927 0.351)
			(end -0.725 0.551)
			(stroke
				(width 0.15)
				(type solid)
			)
			(layer "B.SilkS")
		)
		(fp_line
			(start -0.927 0.051)
			(end -0.927 0.351)
			(stroke
				(width 0.15)
				(type solid)
			)
			(layer "B.SilkS")
		)
		(fp_circle
			(center -0.9652 -0.9652)
			(end -0.9152 -0.9652)
			(stroke
				(width 0.15)
				(type solid)
			)
			(fill yes)
			(layer "B.SilkS")
		)
		(fp_line
			(start -1.12 1.16)
			(end 1.1 1.16)
			(stroke
				(width 0.05)
				(type solid)
			)
			(layer "B.CrtYd")
		)
		(fp_line
			(start -1.12 1.16)
			(end -1.12 -1.15)
			(stroke
				(width 0.05)
				(type solid)
			)
			(layer "B.CrtYd")
		)
		(fp_line
			(start 1.1 1.16)
			(end 1.1 -1.15)
			(stroke
				(width 0.05)
				(type solid)
			)
			(layer "B.CrtYd")
		)
		(fp_line
			(start -1.12 -1.15)
			(end 1.1 -1.15)
			(stroke
				(width 0.05)
				(type solid)
			)
			(layer "B.CrtYd")
		)
		(fp_line
			(start -0.652 0.425)
			(end -0.802 0.276)
			(stroke
				(width 0.15)
				(type solid)
			)
			(layer "B.Fab")
		)
		(fp_line
			(start 0.8 0.425)
			(end -0.652 0.425)
			(stroke
				(width 0.15)
				(type solid)
			)
			(layer "B.Fab")
		)
		(fp_line
			(start 0.8 0.425)
			(end 0.8 -0.424)
			(stroke
				(width 0.15)
				(type solid)
			)
			(layer "B.Fab")
		)
		(fp_line
			(start -0.802 0.276)
			(end -0.802 -0.424)
			(stroke
				(width 0.15)
				(type solid)
			)
			(layer "B.Fab")
		)
		(fp_line
			(start 0.8 -0.424)
			(end -0.802 -0.424)
			(stroke
				(width 0.15)
				(type solid)
			)
			(layer "B.Fab")
		)
		(fp_circle
			(center -0.9652 -0.9652)
			(end -0.9144 -0.9652)
			(stroke
				(width 0.15)
				(type solid)
			)
			(fill no)
			(layer "B.Fab")
		)
		(fp_text user "License: Apache-2.0"
			(at -1.12 -5.024 90)
			(layer "B.Fab")
			(effects
				(font
					(size 0.7 0.7)
					(thickness 0.15)
				)
				(justify left bottom mirror)
			)
		)
		(fp_text user "Author: Antmicro"
			(at -1.12 -6.224 90)
			(layer "B.Fab")
			(effects
				(font
					(size 0.7 0.7)
					(thickness 0.15)
				)
				(justify left bottom mirror)
			)
		)
		(fp_text user "${REFERENCE}"
			(at -1.12 -3.824 90)
			(layer "B.Fab")
			(effects
				(font
					(size 0.7 0.7)
					(thickness 0.15)
				)
				(justify left bottom mirror)
			)
		)
		(pad "1" smd rect
			(at -0.5 -0.65 270)
			(size 0.4 0.51)
			(layers "B.Cu" "B.Mask" "B.Paste")
			(net 371 "/Expansion connector/GPIO.USER_LED1")
			(pinfunction "G")
			(pintype "input")
		)
		(pad "2" smd rect
			(at 0.498 -0.65 270)
			(size 0.4 0.51)
			(layers "B.Cu" "B.Mask" "B.Paste")
			(net 1 "GND")
			(pinfunction "S")
			(pintype "passive")
		)
		(pad "3" smd rect
			(at 0 0.652 270)
			(size 0.4 0.51)
			(layers "B.Cu" "B.Mask" "B.Paste")
			(net 39 "Net-(D36-C)")
			(pinfunction "D")
			(pintype "passive")
		)
	)
	(footprint "antmicro-footprints:R_0402_1005Metric"
		(layer "B.Cu")
		(at 208.716532 141 180)
		(descr "Resistor SMD 0402")
		(tags "resistor SMD 0402")
		(property "Reference" "R199"
			(at -3.809468 -0.5 0)
			(layer "B.SilkS")
			(effects
				(font
					(size 0.7 0.7)
					(thickness 0.15)
				)
				(justify left bottom mirror)
			)
		)
		(property "Value" "R_0R_0402"
			(at -1.011843 -1.772047 0)
			(layer "B.Fab")
			(effects
				(font
					(size 0.7 0.7)
					(thickness 0.15)
				)
				(justify left bottom mirror)
			)
		)
		(property "Datasheet" "https://industrial.panasonic.com/cdbs/www-data/pdf/RDA0000/AOA0000C301.pdf"
			(at 0 0 0)
			(layer "B.Fab")
			(hide yes)
			(effects
				(font
					(size 1.27 1.27)
					(thickness 0.15)
				)
				(justify mirror)
			)
		)
		(property "Description" "SMD Chip Resistor, Jumper, 0 ohm, 100 mW, 0402 [1005 Metric], Thick Film, General Purpose"
			(at 0 0 0)
			(layer "B.Fab")
			(hide yes)
			(effects
				(font
					(size 1.27 1.27)
					(thickness 0.15)
				)
				(justify mirror)
			)
		)
		(property "MPN" "ERJ2GE0R00X"
			(at 0 0 0)
			(unlocked yes)
			(layer "B.Fab")
			(hide yes)
			(effects
				(font
					(size 1 1)
					(thickness 0.15)
				)
				(justify mirror)
			)
		)
		(property "Manufacturer" "Panasonic"
			(at 0 0 0)
			(unlocked yes)
			(layer "B.Fab")
			(hide yes)
			(effects
				(font
					(size 1 1)
					(thickness 0.15)
				)
				(justify mirror)
			)
		)
		(property "License" "Apache-2.0"
			(at 0 0 0)
			(unlocked yes)
			(layer "B.Fab")
			(hide yes)
			(effects
				(font
					(size 1 1)
					(thickness 0.15)
				)
				(justify mirror)
			)
		)
		(property "Author" "Antmicro"
			(at 0 0 0)
			(unlocked yes)
			(layer "B.Fab")
			(hide yes)
			(effects
				(font
					(size 1 1)
					(thickness 0.15)
				)
				(justify mirror)
			)
		)
		(property "Val" "0R"
			(at 0 0 0)
			(unlocked yes)
			(layer "B.Fab")
			(hide yes)
			(effects
				(font
					(size 1 1)
					(thickness 0.15)
				)
				(justify mirror)
			)
		)
		(property "Tolerance" "~"
			(at 0 0 0)
			(unlocked yes)
			(layer "B.Fab")
			(hide yes)
			(effects
				(font
					(size 1 1)
					(thickness 0.15)
				)
				(justify mirror)
			)
		)
		(property "Current" "1A"
			(at 0 0 0)
			(unlocked yes)
			(layer "B.Fab")
			(hide yes)
			(effects
				(font
					(size 1 1)
					(thickness 0.15)
				)
				(justify mirror)
			)
		)
		(sheetname "/SFP/")
		(sheetfile "sfp.kicad_sch")
		(attr smd)
		(fp_rect
			(start -0.925 0.47)
			(end 0.925 -0.47)
			(stroke
				(width 0.05)
				(type default)
			)
			(fill no)
			(layer "B.CrtYd")
		)
		(fp_rect
			(start -0.5 0.25)
			(end 0.5 -0.25)
			(stroke
				(width 0.15)
				(type solid)
			)
			(fill no)
			(layer "B.Fab")
		)
		(fp_text user "${REFERENCE}"
			(at -0.95 -3.168 0)
			(layer "B.Fab")
			(effects
				(font
					(size 0.7 0.7)
					(thickness 0.15)
				)
				(justify left bottom mirror)
			)
		)
		(fp_text user "Author: Antmicro"
			(at -0.95 -4.169 0)
			(layer "B.Fab")
			(effects
				(font
					(size 0.7 0.7)
					(thickness 0.15)
				)
				(justify left bottom mirror)
			)
		)
		(fp_text user "License: Apache-2.0"
			(at -0.95 -5.169 0)
			(layer "B.Fab")
			(effects
				(font
					(size 0.7 0.7)
					(thickness 0.15)
				)
				(justify left bottom mirror)
			)
		)
		(pad "1" smd roundrect
			(at -0.48 0 180)
			(size 0.59 0.64)
			(layers "B.Cu" "B.Mask" "B.Paste")
			(roundrect_rratio 0.25)
			(net 1 "GND")
			(pintype "passive")
		)
		(pad "2" smd roundrect
			(at 0.48 0 180)
			(size 0.59 0.64)
			(layers "B.Cu" "B.Mask" "B.Paste")
			(roundrect_rratio 0.25)
			(net 1369 "Net-(J12-RS1)")
			(pintype "passive")
		)
	)
)
